(kicad_pcb
	(version 20260206)
	(generator "pcbnew")
	(generator_version "10.0")
	(general
		(thickness 1.6)
		(legacy_teardrops no)
	)
	(paper "A4")
	(title_block
		(title "v1-tray-backplane — T6M_tray_BP_c_1023_1120.brd")
		(comment 1 "Open CloudServer (Microsoft) / footprints 135-137 of 170")
	)
	(layers
		(0 "F.Cu" signal "TOP")
		(4 "In1.Cu" signal "GND")
		(6 "In2.Cu" signal "IN1")
		(8 "In3.Cu" signal "VCC")
		(10 "In4.Cu" signal "VCC1")
		(12 "In5.Cu" signal "IN2")
		(14 "In6.Cu" signal "GND1")
		(2 "B.Cu" signal "BOTTOM")
		(9 "F.Adhes" user "F.Adhesive")
		(11 "B.Adhes" user "B.Adhesive")
		(13 "F.Paste" user "Package Geometry/Pastemask Top")
		(15 "B.Paste" user "Package Geometry/Pastemask Bottom")
		(5 "F.SilkS" user "Ref Des/Silkscreen Top")
		(7 "B.SilkS" user "Ref Des/Silkscreen Bottom")
		(1 "F.Mask" user "Board Geometry/Soldermask Top")
		(3 "B.Mask" user "Board Geometry/Soldermask Bottom")
		(17 "Dwgs.User" user "User.Drawings")
		(19 "Cmts.User" user "User.Comments")
		(21 "Eco1.User" user "User.Eco1")
		(23 "Eco2.User" user "User.Eco2")
		(25 "Edge.Cuts" user "Board Geometry/Outline")
		(27 "Margin" user)
		(31 "F.CrtYd" user "Package Geometry/Place Bound Top")
		(29 "B.CrtYd" user "Package Geometry/Place Bound Bottom")
		(35 "F.Fab" user "Ref Des/Assembly Top")
		(33 "B.Fab" user "Ref Des/Assembly Bottom")
	)
	(footprint ""
		(layer "F.Cu")
		(at 130.146552 -22.210268)
		(property "Reference" "R67"
			(at -61.8236 5.140452 0)
			(unlocked yes)
			(layer "F.SilkS")
			(effects
				(font
					(size 0.7874 0.5842)
					(thickness 0.1524)
				)
				(justify left)
			)
		)
		(property "Value" ""
			(at 0 0 0)
			(layer "F.Fab")
			(effects
				(font
					(size 1.27 1.27)
				)
			)
		)
		(duplicate_pad_numbers_are_jumpers no)
		(fp_line
			(start -0.7874 -0.4064)
			(end 0.7874 -0.4064)
			(stroke
				(width 0.1524)
				(type default)
			)
			(layer "F.SilkS")
		)
		(fp_line
			(start -0.7874 0.4064)
			(end -0.7874 -0.4064)
			(stroke
				(width 0.1524)
				(type default)
			)
			(layer "F.SilkS")
		)
		(fp_line
			(start 0.7874 -0.4064)
			(end 0.7874 0.4064)
			(stroke
				(width 0.1524)
				(type default)
			)
			(layer "F.SilkS")
		)
		(fp_line
			(start 0.7874 0.4064)
			(end -0.7874 0.4064)
			(stroke
				(width 0.1524)
				(type default)
			)
			(layer "F.SilkS")
		)
		(fp_poly
			(pts
				(xy -0.508 0.2794) (xy -0.508 0.2286) (xy -0.635 0.2286) (xy -0.635 -0.254) (xy -0.5334 -0.254)
				(xy -0.5334 -0.2794) (xy 0.5334 -0.2794) (xy 0.5334 -0.254) (xy 0.635 -0.254) (xy 0.635 0.254) (xy 0.5334 0.254)
				(xy 0.5334 0.2794)
			)
			(stroke
				(width 0)
				(type default)
			)
			(fill no)
			(layer "F.CrtYd")
		)
		(pad "1" smd rect
			(at 0.40005 0)
			(size 0.4572 0.508)
			(layers "F.Cu" "F.Mask" "F.Paste")
			(net "ENET10G_1_LOS")
		)
		(pad "2" smd rect
			(at -0.40005 0)
			(size 0.4572 0.508)
			(layers "F.Cu" "F.Mask" "F.Paste")
			(net "SFP1_PRESENT_N")
		)
	)
	(footprint ""
		(layer "F.Cu")
		(at 312.1406 -32.065468)
		(property "Reference" "R83"
			(at -1.3716 -8.88873 0)
			(unlocked yes)
			(layer "F.SilkS")
			(effects
				(font
					(size 0.7874 0.5842)
					(thickness 0.1524)
				)
				(justify left)
			)
		)
		(property "Value" ""
			(at 0 0 0)
			(layer "F.Fab")
			(effects
				(font
					(size 1.27 1.27)
				)
			)
		)
		(duplicate_pad_numbers_are_jumpers no)
		(fp_line
			(start -1.905 -0.8636)
			(end 1.905 -0.8636)
			(stroke
				(width 0.1524)
				(type default)
			)
			(layer "F.SilkS")
		)
		(fp_line
			(start -1.905 0.8636)
			(end -1.905 -0.8636)
			(stroke
				(width 0.1524)
				(type default)
			)
			(layer "F.SilkS")
		)
		(fp_line
			(start 1.905 -0.8636)
			(end 1.905 0.8636)
			(stroke
				(width 0.1524)
				(type default)
			)
			(layer "F.SilkS")
		)
		(fp_line
			(start 1.905 0.8636)
			(end -1.905 0.8636)
			(stroke
				(width 0.1524)
				(type default)
			)
			(layer "F.SilkS")
		)
		(fp_poly
			(pts
				(xy 1.524 0.6858) (xy 1.524 -0.6858) (xy 1.524 -0.7366) (xy -1.524 -0.7366) (xy -1.524 -0.6858)
				(xy -1.524 0.6858) (xy -1.524 0.7366) (xy 1.524 0.7366)
			)
			(stroke
				(width 0)
				(type default)
			)
			(fill no)
			(layer "F.CrtYd")
		)
		(pad "1" smd rect
			(at 0.94996 0)
			(size 1.1176 1.3716)
			(layers "F.Cu" "F.Mask" "F.Paste")
			(net "P3V3_BLAD2")
		)
		(pad "2" smd rect
			(at -0.94996 0)
			(size 1.1176 1.3716)
			(layers "F.Cu" "F.Mask" "F.Paste")
			(net "P3V3_10G_4_VCCR")
		)
	)
	(footprint ""
		(layer "F.Cu")
		(at 375.82856 -27.776678 180)
		(property "Reference" "R31"
			(at -33.83788 -17.234408 0)
			(unlocked yes)
			(layer "F.SilkS")
			(effects
				(font
					(size 0.7874 0.5842)
					(thickness 0.1524)
				)
				(justify left)
			)
		)
		(property "Value" ""
			(at 0 0 180)
			(layer "F.Fab")
			(effects
				(font
					(size 1.27 1.27)
				)
			)
		)
		(duplicate_pad_numbers_are_jumpers no)
		(fp_line
			(start 0.7874 0.4064)
			(end -0.7874 0.4064)
			(stroke
				(width 0.1524)
				(type default)
			)
			(layer "F.SilkS")
		)
		(fp_line
			(start 0.7874 -0.4064)
			(end 0.7874 0.4064)
			(stroke
				(width 0.1524)
				(type default)
			)
			(layer "F.SilkS")
		)
		(fp_line
			(start -0.7874 0.4064)
			(end -0.7874 -0.4064)
			(stroke
				(width 0.1524)
				(type default)
			)
			(layer "F.SilkS")
		)
		(fp_line
			(start -0.7874 -0.4064)
			(end 0.7874 -0.4064)
			(stroke
				(width 0.1524)
				(type default)
			)
			(layer "F.SilkS")
		)
		(fp_poly
			(pts
				(xy -0.508 0.2794) (xy -0.508 0.2286) (xy -0.635 0.2286) (xy -0.635 -0.254) (xy -0.5334 -0.254)
				(xy -0.5334 -0.2794) (xy 0.5334 -0.2794) (xy 0.5334 -0.254) (xy 0.635 -0.254) (xy 0.635 0.254) (xy 0.5334 0.254)
				(xy 0.5334 0.2794)
			)
			(stroke
				(width 0)
				(type default)
			)
			(fill no)
			(layer "F.CrtYd")
		)
		(pad "1" smd rect
			(at 0.40005 0 180)
			(size 0.4572 0.508)
			(layers "F.Cu" "F.Mask" "F.Paste")
			(net "P3V3_BLAD2")
		)
		(pad "2" smd rect
			(at -0.40005 0 180)
			(size 0.4572 0.508)
			(layers "F.Cu" "F.Mask" "F.Paste")
			(net "ENET10G_3_RS1")
		)
	)
)
